# T6G (Grand Teton) — schematic netlist excerpt (pin names and nets, part order shuffled) for the footprints in the layout excerpt that follows; sources: Cadence DE-HDL packaged netlist, KiCad conversion of 04192023_DAF0TMB3IC0_F0TG_MB_C_brd_V02_OCP.brd

R6168  Q_RES  1K 1% CHIP  pkg 0402LF  page 112 : A = FM_P2E_BUF2_VODB_DB ; B = GND
R2843  Q_RES  4.7K 1% CHIP  pkg 0402LF  page 257 : A = P3V3_ADC ; B = GND

(kicad_pcb
	(version 20260206)
	(generator "pcbnew")
	(generator_version "10.0")
	(general
		(thickness 1.6)
		(legacy_teardrops no)
	)
	(paper "A4")
	(title_block
		(title "04192023_DAF0TMB3IC0_F0TG_MB_C_brd_V02_OCP.brd")
		(comment 1 "Grand Teton / footprints 2758-2759 of 8354")
	)
	(layers
		(0 "F.Cu" signal "TOP")
		(4 "In1.Cu" signal "GND")
		(6 "In2.Cu" signal "IN1")
		(8 "In3.Cu" signal "GND1")
		(10 "In4.Cu" signal "IN2")
		(12 "In5.Cu" signal "GND2")
		(14 "In6.Cu" signal "IN3")
		(16 "In7.Cu" signal "GND3")
		(18 "In8.Cu" signal "VCC")
		(20 "In9.Cu" signal "VCC1")
		(22 "In10.Cu" signal "GND4")
		(24 "In11.Cu" signal "IN4")
		(26 "In12.Cu" signal "GND5")
		(28 "In13.Cu" signal "IN5")
		(30 "In14.Cu" signal "GND6")
		(32 "In15.Cu" signal "IN6")
		(34 "In16.Cu" signal "GND7")
		(2 "B.Cu" signal "BOTTOM")
		(9 "F.Adhes" user "F.Adhesive")
		(11 "B.Adhes" user "B.Adhesive")
		(13 "F.Paste" user "Package Geometry/Pastemask Top")
		(15 "B.Paste" user "Package Geometry/Pastemask Bottom")
		(5 "F.SilkS" user "Ref Des/Silkscreen Top")
		(7 "B.SilkS" user "Ref Des/Silkscreen Bottom")
		(1 "F.Mask" user "Board Geometry/Soldermask Top")
		(3 "B.Mask" user "Board Geometry/Soldermask Bottom")
		(17 "Dwgs.User" user "User.Drawings")
		(19 "Cmts.User" user "User.Comments")
		(21 "Eco1.User" user "User.Eco1")
		(23 "Eco2.User" user "User.Eco2")
		(25 "Edge.Cuts" user "Board Geometry/Outline")
		(27 "Margin" user)
		(31 "F.CrtYd" user "Package Geometry/Place Bound Top")
		(29 "B.CrtYd" user "Package Geometry/Place Bound Bottom")
		(35 "F.Fab" user "Ref Des/Assembly Top")
		(33 "B.Fab" user "Ref Des/Assembly Bottom")
	)
	(footprint ""
		(layer "F.Cu")
		(at 13.621258 -427.098206 180)
		(property "Reference" "R6168"
			(at 0 0 180)
			(layer "F.SilkS")
			(hide yes)
			(effects
				(font
					(size 1.27 1.27)
				)
			)
		)
		(property "Value" ""
			(at 0 0 180)
			(layer "F.Fab")
			(effects
				(font
					(size 1.27 1.27)
				)
			)
		)
		(duplicate_pad_numbers_are_jumpers no)
		(fp_line
			(start 0.7874 0.4064)
			(end -0.7874 0.4064)
			(stroke
				(width 0.1524)
				(type default)
			)
			(layer "F.SilkS")
		)
		(fp_line
			(start 0.7874 -0.4064)
			(end 0.7874 0.4064)
			(stroke
				(width 0.1524)
				(type default)
			)
			(layer "F.SilkS")
		)
		(fp_line
			(start -0.7874 0.4064)
			(end -0.7874 -0.4064)
			(stroke
				(width 0.1524)
				(type default)
			)
			(layer "F.SilkS")
		)
		(fp_line
			(start -0.7874 -0.4064)
			(end 0.7874 -0.4064)
			(stroke
				(width 0.1524)
				(type default)
			)
			(layer "F.SilkS")
		)
		(fp_line
			(start 0.67945 0.3048)
			(end 0.120396 0.3048)
			(stroke
				(width 0.1)
				(type default)
			)
			(layer "F.Fab")
		)
		(fp_line
			(start 0.67945 -0.3048)
			(end 0.67945 0.3048)
			(stroke
				(width 0.1)
				(type default)
			)
			(layer "F.Fab")
		)
		(fp_line
			(start 0.12065 -0.2794)
			(end 0.12065 -0.3048)
			(stroke
				(width 0.1)
				(type default)
			)
			(layer "F.Fab")
		)
		(fp_line
			(start 0.12065 -0.3048)
			(end 0.67945 -0.3048)
			(stroke
				(width 0.1)
				(type default)
			)
			(layer "F.Fab")
		)
		(fp_line
			(start 0.120396 0.3048)
			(end 0.120396 0.2794)
			(stroke
				(width 0.1)
				(type default)
			)
			(layer "F.Fab")
		)
		(fp_line
			(start 0.120396 0.2794)
			(end -0.12065 0.2794)
			(stroke
				(width 0.1)
				(type default)
			)
			(layer "F.Fab")
		)
		(fp_line
			(start -0.12065 0.3048)
			(end -0.67945 0.3048)
			(stroke
				(width 0.1)
				(type default)
			)
			(layer "F.Fab")
		)
		(fp_line
			(start -0.12065 0.2794)
			(end -0.12065 0.3048)
			(stroke
				(width 0.1)
				(type default)
			)
			(layer "F.Fab")
		)
		(fp_line
			(start -0.12065 -0.2794)
			(end 0.12065 -0.2794)
			(stroke
				(width 0.1)
				(type default)
			)
			(layer "F.Fab")
		)
		(fp_line
			(start -0.12065 -0.305054)
			(end -0.12065 -0.2794)
			(stroke
				(width 0.1)
				(type default)
			)
			(layer "F.Fab")
		)
		(fp_line
			(start -0.67945 0.3048)
			(end -0.67945 -0.305054)
			(stroke
				(width 0.1)
				(type default)
			)
			(layer "F.Fab")
		)
		(fp_line
			(start -0.67945 -0.305054)
			(end -0.12065 -0.305054)
			(stroke
				(width 0.1)
				(type default)
			)
			(layer "F.Fab")
		)
		(pad "1" smd circle
			(at -0.40005 0 180)
			(size 0 0)
			(layers "F.Cu" "F.Mask" "F.Paste")
			(net "FM_P2E_BUF2_VODB_DB")
		)
		(pad "2" smd circle
			(at 0.40005 0 180)
			(size 0 0)
			(layers "F.Cu" "F.Mask" "F.Paste")
			(net "GND")
		)
	)
	(footprint ""
		(layer "F.Cu")
		(at 327.179178 -42.176954)
		(property "Reference" "R2843"
			(at 0 0 0)
			(layer "F.SilkS")
			(hide yes)
			(effects
				(font
					(size 1.27 1.27)
				)
			)
		)
		(property "Value" ""
			(at 0 0 0)
			(layer "F.Fab")
			(effects
				(font
					(size 1.27 1.27)
				)
			)
		)
		(duplicate_pad_numbers_are_jumpers no)
		(fp_line
			(start -0.7874 -0.4064)
			(end 0.7874 -0.4064)
			(stroke
				(width 0.1524)
				(type default)
			)
			(layer "F.SilkS")
		)
		(fp_line
			(start -0.7874 0.4064)
			(end -0.7874 -0.4064)
			(stroke
				(width 0.1524)
				(type default)
			)
			(layer "F.SilkS")
		)
		(fp_line
			(start 0.7874 -0.4064)
			(end 0.7874 0.4064)
			(stroke
				(width 0.1524)
				(type default)
			)
			(layer "F.SilkS")
		)
		(fp_line
			(start 0.7874 0.4064)
			(end -0.7874 0.4064)
			(stroke
				(width 0.1524)
				(type default)
			)
			(layer "F.SilkS")
		)
		(fp_line
			(start -0.67945 -0.305054)
			(end -0.12065 -0.305054)
			(stroke
				(width 0.1)
				(type default)
			)
			(layer "F.Fab")
		)
		(fp_line
			(start -0.67945 0.3048)
			(end -0.67945 -0.305054)
			(stroke
				(width 0.1)
				(type default)
			)
			(layer "F.Fab")
		)
		(fp_line
			(start -0.12065 -0.305054)
			(end -0.12065 -0.2794)
			(stroke
				(width 0.1)
				(type default)
			)
			(layer "F.Fab")
		)
		(fp_line
			(start -0.12065 -0.2794)
			(end 0.12065 -0.2794)
			(stroke
				(width 0.1)
				(type default)
			)
			(layer "F.Fab")
		)
		(fp_line
			(start -0.12065 0.2794)
			(end -0.12065 0.3048)
			(stroke
				(width 0.1)
				(type default)
			)
			(layer "F.Fab")
		)
		(fp_line
			(start -0.12065 0.3048)
			(end -0.67945 0.3048)
			(stroke
				(width 0.1)
				(type default)
			)
			(layer "F.Fab")
		)
		(fp_line
			(start 0.120396 0.2794)
			(end -0.12065 0.2794)
			(stroke
				(width 0.1)
				(type default)
			)
			(layer "F.Fab")
		)
		(fp_line
			(start 0.120396 0.3048)
			(end 0.120396 0.2794)
			(stroke
				(width 0.1)
				(type default)
			)
			(layer "F.Fab")
		)
		(fp_line
			(start 0.12065 -0.3048)
			(end 0.67945 -0.3048)
			(stroke
				(width 0.1)
				(type default)
			)
			(layer "F.Fab")
		)
		(fp_line
			(start 0.12065 -0.2794)
			(end 0.12065 -0.3048)
			(stroke
				(width 0.1)
				(type default)
			)
			(layer "F.Fab")
		)
		(fp_line
			(start 0.67945 -0.3048)
			(end 0.67945 0.3048)
			(stroke
				(width 0.1)
				(type default)
			)
			(layer "F.Fab")
		)
		(fp_line
			(start 0.67945 0.3048)
			(end 0.120396 0.3048)
			(stroke
				(width 0.1)
				(type default)
			)
			(layer "F.Fab")
		)
		(pad "1" smd circle
			(at -0.40005 0)
			(size 0 0)
			(layers "F.Cu" "F.Mask" "F.Paste")
			(net "P3V3_ADC")
		)
		(pad "2" smd circle
			(at 0.40005 0)
			(size 0 0)
			(layers "F.Cu" "F.Mask" "F.Paste")
			(net "GND")
		)
	)
)
